# BASEBOARD_FAB2 (Tioga Pass) — schematic netlist excerpt (pin names and nets, part order shuffled) for the footprints in the layout excerpt that follows; sources: Cadence DE-HDL packaged netlist, KiCad conversion of Wiwynn_Tioga_Pass_MB.brd

R25W159  RES  1.00K 1% CHIP  pkg 0402  page 254 : A = GND ; B = PD_GTL2014_3_VREF
C5P19  CAP  100UF 4V 20% X5R  pkg 0805  page 42 : A = PVCCMCP_CPU0 ; B = GND
R2T41  RES  22.1 1.0% CHIP  pkg 0402  page 145 : A = IRQ_FORCE_NM_THROTTLE_N ; B = FM_BMC_SYS_THROTTLE_R_N

(kicad_pcb
	(version 20260206)
	(generator "pcbnew")
	(generator_version "10.0")
	(general
		(thickness 1.6)
		(legacy_teardrops no)
	)
	(paper "A4")
	(title_block
		(title "Wiwynn_Tioga_Pass_MB.brd")
		(comment 1 "Tioga Pass / footprints 3156-3158 of 4770")
	)
	(layers
		(0 "F.Cu" signal "TOP")
		(4 "In1.Cu" signal "L2GND")
		(6 "In2.Cu" signal "L3")
		(8 "In3.Cu" signal "L4GND")
		(10 "In4.Cu" signal "L5")
		(12 "In5.Cu" signal "L6GND")
		(14 "In6.Cu" signal "L7VCC")
		(16 "In7.Cu" signal "L8VCC")
		(18 "In8.Cu" signal "L9GND")
		(20 "In9.Cu" signal "L10")
		(22 "In10.Cu" signal "L11GND")
		(24 "In11.Cu" signal "L12")
		(26 "In12.Cu" signal "L13GND")
		(2 "B.Cu" signal "BOTTOM")
		(9 "F.Adhes" user "F.Adhesive")
		(11 "B.Adhes" user "B.Adhesive")
		(13 "F.Paste" user "Package Geometry/Pastemask Top")
		(15 "B.Paste" user "Package Geometry/Pastemask Bottom")
		(5 "F.SilkS" user "Ref Des/Silkscreen Top")
		(7 "B.SilkS" user "Ref Des/Silkscreen Bottom")
		(1 "F.Mask" user "Board Geometry/Soldermask Top")
		(3 "B.Mask" user "Board Geometry/Soldermask Bottom")
		(17 "Dwgs.User" user "User.Drawings")
		(19 "Cmts.User" user "User.Comments")
		(21 "Eco1.User" user "User.Eco1")
		(23 "Eco2.User" user "User.Eco2")
		(25 "Edge.Cuts" user "Board Geometry/Outline")
		(27 "Margin" user)
		(31 "F.CrtYd" user "Package Geometry/Place Bound Top")
		(29 "B.CrtYd" user "Package Geometry/Place Bound Bottom")
		(35 "F.Fab" user "Ref Des/Assembly Top")
		(33 "B.Fab" user "Ref Des/Assembly Bottom")
	)
	(footprint ""
		(layer "B.Cu")
		(at 273.179286 -77.82814)
		(property "Reference" "C5P19"
			(at 0 0 0)
			(layer "B.SilkS")
			(hide yes)
			(effects
				(font
					(size 1.27 1.27)
				)
				(justify mirror)
			)
		)
		(property "Value" ""
			(at 0 0 0)
			(layer "B.Fab")
			(effects
				(font
					(size 1.27 1.27)
				)
				(justify mirror)
			)
		)
		(duplicate_pad_numbers_are_jumpers no)
		(fp_poly
			(pts
				(xy 0.7239 -0.2159) (xy -0.7239 -0.2159) (xy -0.7239 1.9939) (xy 0.7239 1.9939)
			)
			(stroke
				(width 0)
				(type default)
			)
			(fill no)
			(layer "B.CrtYd")
		)
		(fp_line
			(start -0.7239 -0.2159)
			(end 0.7239 -0.2159)
			(stroke
				(width 0.1)
				(type default)
			)
			(layer "B.Fab")
		)
		(fp_line
			(start -0.7239 1.9939)
			(end -0.7239 -0.2159)
			(stroke
				(width 0.1)
				(type default)
			)
			(layer "B.Fab")
		)
		(fp_line
			(start 0.7239 -0.2159)
			(end 0.7239 1.9939)
			(stroke
				(width 0.1)
				(type default)
			)
			(layer "B.Fab")
		)
		(fp_line
			(start 0.7239 1.9939)
			(end -0.7239 1.9939)
			(stroke
				(width 0.1)
				(type default)
			)
			(layer "B.Fab")
		)
		(pad "1" smd rect
			(at 0 0 180)
			(size 1.27 1.016)
			(layers "B.Cu" "B.Mask" "B.Paste")
			(net "PVCCMCP_CPU0")
		)
		(pad "2" smd rect
			(at 0 1.778 180)
			(size 1.27 1.016)
			(layers "B.Cu" "B.Mask" "B.Paste")
			(net "GND")
		)
		(zone
			(layer "B.Cu")
			(hatch none 0.5)
			(connect_pads
				(clearance 0)
			)
			(min_thickness 0.25)
			(keepout
				(tracks not_allowed)
				(vias allowed)
				(pads allowed)
				(copperpour not_allowed)
				(footprints allowed)
			)
			(placement
				(enabled no)
				(sheetname "")
			)
			(fill
				(thermal_gap 0.5)
				(thermal_bridge_width 0.5)
				(island_removal_mode 0)
			)
			(polygon
				(pts
					(xy 273.814286 -77.32014) (xy 272.544286 -77.32014) (xy 272.544286 -76.55814) (xy 273.814286 -76.55814)
				)
			)
		)
	)
	(footprint ""
		(layer "B.Cu")
		(at 449.6816 -142.8623 90)
		(property "Reference" "R25W159"
			(at 0.8382 -0.67818 90)
			(unlocked yes)
			(layer "B.SilkS")
			(effects
				(font
					(size 0.4064 0.254)
					(thickness 0.1524)
				)
				(justify left mirror)
			)
		)
		(property "Value" ""
			(at 0 0 90)
			(layer "B.Fab")
			(effects
				(font
					(size 1.27 1.27)
				)
				(justify mirror)
			)
		)
		(duplicate_pad_numbers_are_jumpers no)
		(fp_poly
			(pts
				(xy 0.2794 -0.1016) (xy -0.2794 -0.1016) (xy -0.2794 0.9906) (xy 0.2794 0.9906)
			)
			(stroke
				(width 0)
				(type default)
			)
			(fill no)
			(layer "B.CrtYd")
		)
		(fp_line
			(start 0.2794 -0.1016)
			(end 0.2794 0.9906)
			(stroke
				(width 0.1)
				(type default)
			)
			(layer "B.Fab")
		)
		(fp_line
			(start -0.2794 -0.1016)
			(end 0.2794 -0.1016)
			(stroke
				(width 0.1)
				(type default)
			)
			(layer "B.Fab")
		)
		(fp_line
			(start 0.2794 0.9906)
			(end -0.2794 0.9906)
			(stroke
				(width 0.1)
				(type default)
			)
			(layer "B.Fab")
		)
		(fp_line
			(start -0.2794 0.9906)
			(end -0.2794 -0.1016)
			(stroke
				(width 0.1)
				(type default)
			)
			(layer "B.Fab")
		)
		(pad "1" smd rect
			(at 0 0 270)
			(size 0.508 0.508)
			(layers "B.Cu" "B.Mask" "B.Paste")
			(net "GND")
		)
		(pad "2" smd rect
			(at 0 0.889 270)
			(size 0.508 0.508)
			(layers "B.Cu" "B.Mask" "B.Paste")
			(net "PD_GTL2014_3_VREF")
		)
		(zone
			(layer "B.Cu")
			(hatch none 0.5)
			(connect_pads
				(clearance 0)
			)
			(min_thickness 0.25)
			(keepout
				(tracks allowed)
				(vias not_allowed)
				(pads allowed)
				(copperpour not_allowed)
				(footprints allowed)
			)
			(placement
				(enabled no)
				(sheetname "")
			)
			(fill
				(thermal_gap 0.5)
				(thermal_bridge_width 0.5)
				(island_removal_mode 0)
			)
			(polygon
				(pts
					(xy 449.9356 -143.1163) (xy 449.9356 -142.6083) (xy 450.3166 -142.6083) (xy 450.3166 -143.1163)
				)
			)
		)
		(zone
			(layer "B.Cu")
			(hatch none 0.5)
			(connect_pads
				(clearance 0)
			)
			(min_thickness 0.25)
			(keepout
				(tracks not_allowed)
				(vias allowed)
				(pads allowed)
				(copperpour not_allowed)
				(footprints allowed)
			)
			(placement
				(enabled no)
				(sheetname "")
			)
			(fill
				(thermal_gap 0.5)
				(thermal_bridge_width 0.5)
				(island_removal_mode 0)
			)
			(polygon
				(pts
					(xy 450.3166 -143.1163) (xy 450.3166 -142.6083) (xy 449.9356 -142.6083) (xy 449.9356 -143.1163)
				)
			)
		)
	)
	(footprint ""
		(layer "B.Cu")
		(at 405.60371 -37.940234)
		(property "Reference" "R2T41"
			(at 0.8382 -0.67818 0)
			(unlocked yes)
			(layer "B.SilkS")
			(effects
				(font
					(size 0.4064 0.254)
					(thickness 0.1524)
				)
				(justify left mirror)
			)
		)
		(property "Value" ""
			(at 0 0 0)
			(layer "B.Fab")
			(effects
				(font
					(size 1.27 1.27)
				)
				(justify mirror)
			)
		)
		(duplicate_pad_numbers_are_jumpers no)
		(fp_poly
			(pts
				(xy 0.2794 -0.1016) (xy -0.2794 -0.1016) (xy -0.2794 0.9906) (xy 0.2794 0.9906)
			)
			(stroke
				(width 0)
				(type default)
			)
			(fill no)
			(layer "B.CrtYd")
		)
		(fp_line
			(start -0.2794 -0.1016)
			(end 0.2794 -0.1016)
			(stroke
				(width 0.1)
				(type default)
			)
			(layer "B.Fab")
		)
		(fp_line
			(start -0.2794 0.9906)
			(end -0.2794 -0.1016)
			(stroke
				(width 0.1)
				(type default)
			)
			(layer "B.Fab")
		)
		(fp_line
			(start 0.2794 -0.1016)
			(end 0.2794 0.9906)
			(stroke
				(width 0.1)
				(type default)
			)
			(layer "B.Fab")
		)
		(fp_line
			(start 0.2794 0.9906)
			(end -0.2794 0.9906)
			(stroke
				(width 0.1)
				(type default)
			)
			(layer "B.Fab")
		)
		(pad "1" smd rect
			(at 0 0 180)
			(size 0.508 0.508)
			(layers "B.Cu" "B.Mask" "B.Paste")
			(net "IRQ_FORCE_NM_THROTTLE_N")
		)
		(pad "2" smd rect
			(at 0 0.889 180)
			(size 0.508 0.508)
			(layers "B.Cu" "B.Mask" "B.Paste")
			(net "FM_BMC_SYS_THROTTLE_R_N")
		)
		(zone
			(layer "B.Cu")
			(hatch none 0.5)
			(connect_pads
				(clearance 0)
			)
			(min_thickness 0.25)
			(keepout
				(tracks allowed)
				(vias not_allowed)
				(pads allowed)
				(copperpour not_allowed)
				(footprints allowed)
			)
			(placement
				(enabled no)
				(sheetname "")
			)
			(fill
				(thermal_gap 0.5)
				(thermal_bridge_width 0.5)
				(island_removal_mode 0)
			)
			(polygon
				(pts
					(xy 405.85771 -37.686234) (xy 405.34971 -37.686234) (xy 405.34971 -37.305234) (xy 405.85771 -37.305234)
				)
			)
		)
		(zone
			(layer "B.Cu")
			(hatch none 0.5)
			(connect_pads
				(clearance 0)
			)
			(min_thickness 0.25)
			(keepout
				(tracks not_allowed)
				(vias allowed)
				(pads allowed)
				(copperpour not_allowed)
				(footprints allowed)
			)
			(placement
				(enabled no)
				(sheetname "")
			)
			(fill
				(thermal_gap 0.5)
				(thermal_bridge_width 0.5)
				(island_removal_mode 0)
			)
			(polygon
				(pts
					(xy 405.85771 -37.305234) (xy 405.34971 -37.305234) (xy 405.34971 -37.686234) (xy 405.85771 -37.686234)
				)
			)
		)
	)
)
